(kicad_pcb
	(version 20260206)
	(generator "pcbnew")
	(generator_version "10.0")
	(general
		(thickness 1.6)
		(legacy_teardrops no)
	)
	(paper "A4")
	(title_block
		(title "v1-pdb — T6M_PDB_D_0927_0900.brd")
		(comment 1 "Open CloudServer (Microsoft) / footprints 235-238 of 321")
	)
	(layers
		(0 "F.Cu" signal "TOP")
		(4 "In1.Cu" signal "GND")
		(6 "In2.Cu" signal "IN1")
		(8 "In3.Cu" signal "VCC")
		(10 "In4.Cu" signal "VCC1")
		(12 "In5.Cu" signal "IN2")
		(14 "In6.Cu" signal "GND1")
		(2 "B.Cu" signal "BOTTOM")
		(9 "F.Adhes" user "F.Adhesive")
		(11 "B.Adhes" user "B.Adhesive")
		(13 "F.Paste" user "Package Geometry/Pastemask Top")
		(15 "B.Paste" user "Package Geometry/Pastemask Bottom")
		(5 "F.SilkS" user "Ref Des/Silkscreen Top")
		(7 "B.SilkS" user "Ref Des/Silkscreen Bottom")
		(1 "F.Mask" user "Board Geometry/Soldermask Top")
		(3 "B.Mask" user "Board Geometry/Soldermask Bottom")
		(17 "Dwgs.User" user "User.Drawings")
		(19 "Cmts.User" user "User.Comments")
		(21 "Eco1.User" user "User.Eco1")
		(23 "Eco2.User" user "User.Eco2")
		(25 "Edge.Cuts" user "Board Geometry/Outline")
		(27 "Margin" user)
		(31 "F.CrtYd" user "Package Geometry/Place Bound Top")
		(29 "B.CrtYd" user "Package Geometry/Place Bound Bottom")
		(35 "F.Fab" user "Ref Des/Assembly Top")
		(33 "B.Fab" user "Ref Des/Assembly Bottom")
	)
	(footprint ""
		(layer "F.Cu")
		(at 26.001726 -101.689408)
		(property "Reference" "R135"
			(at -4.183888 -0.051562 0)
			(unlocked yes)
			(layer "F.SilkS")
			(effects
				(font
					(size 0.7874 0.5842)
					(thickness 0.1524)
				)
				(justify left)
			)
		)
		(property "Value" ""
			(at 0 0 0)
			(layer "F.Fab")
			(effects
				(font
					(size 1.27 1.27)
				)
			)
		)
		(duplicate_pad_numbers_are_jumpers no)
		(fp_line
			(start -0.7874 -0.4064)
			(end 0.7874 -0.4064)
			(stroke
				(width 0.1524)
				(type default)
			)
			(layer "F.SilkS")
		)
		(fp_line
			(start -0.7874 0.4064)
			(end -0.7874 -0.4064)
			(stroke
				(width 0.1524)
				(type default)
			)
			(layer "F.SilkS")
		)
		(fp_line
			(start 0.7874 -0.4064)
			(end 0.7874 0.4064)
			(stroke
				(width 0.1524)
				(type default)
			)
			(layer "F.SilkS")
		)
		(fp_line
			(start 0.7874 0.4064)
			(end -0.7874 0.4064)
			(stroke
				(width 0.1524)
				(type default)
			)
			(layer "F.SilkS")
		)
		(fp_poly
			(pts
				(xy -0.508 0.2794) (xy -0.508 0.2286) (xy -0.635 0.2286) (xy -0.635 -0.254) (xy -0.5334 -0.254)
				(xy -0.5334 -0.2794) (xy 0.5334 -0.2794) (xy 0.5334 -0.254) (xy 0.635 -0.254) (xy 0.635 0.254) (xy 0.5334 0.254)
				(xy 0.5334 0.2794)
			)
			(stroke
				(width 0)
				(type default)
			)
			(fill no)
			(layer "F.CrtYd")
		)
		(pad "1" smd rect
			(at 0.40005 0)
			(size 0.4572 0.508)
			(layers "F.Cu" "F.Mask" "F.Paste")
			(net "PSU2_CSAHRE")
		)
		(pad "2" smd rect
			(at -0.40005 0)
			(size 0.4572 0.508)
			(layers "F.Cu" "F.Mask" "F.Paste")
			(net "PSU_CSAHRE")
		)
	)
	(footprint ""
		(layer "F.Cu")
		(at 26.492708 -14.7955)
		(property "Reference" "R134"
			(at -3.978148 -0.004826 0)
			(unlocked yes)
			(layer "F.SilkS")
			(effects
				(font
					(size 0.7874 0.5842)
					(thickness 0.1524)
				)
				(justify left)
			)
		)
		(property "Value" ""
			(at 0 0 0)
			(layer "F.Fab")
			(effects
				(font
					(size 1.27 1.27)
				)
			)
		)
		(duplicate_pad_numbers_are_jumpers no)
		(fp_line
			(start -0.7874 -0.4064)
			(end 0.7874 -0.4064)
			(stroke
				(width 0.1524)
				(type default)
			)
			(layer "F.SilkS")
		)
		(fp_line
			(start -0.7874 0.4064)
			(end -0.7874 -0.4064)
			(stroke
				(width 0.1524)
				(type default)
			)
			(layer "F.SilkS")
		)
		(fp_line
			(start 0.7874 -0.4064)
			(end 0.7874 0.4064)
			(stroke
				(width 0.1524)
				(type default)
			)
			(layer "F.SilkS")
		)
		(fp_line
			(start 0.7874 0.4064)
			(end -0.7874 0.4064)
			(stroke
				(width 0.1524)
				(type default)
			)
			(layer "F.SilkS")
		)
		(fp_poly
			(pts
				(xy -0.508 0.2794) (xy -0.508 0.2286) (xy -0.635 0.2286) (xy -0.635 -0.254) (xy -0.5334 -0.254)
				(xy -0.5334 -0.2794) (xy 0.5334 -0.2794) (xy 0.5334 -0.254) (xy 0.635 -0.254) (xy 0.635 0.254) (xy 0.5334 0.254)
				(xy 0.5334 0.2794)
			)
			(stroke
				(width 0)
				(type default)
			)
			(fill no)
			(layer "F.CrtYd")
		)
		(pad "1" smd rect
			(at 0.40005 0)
			(size 0.4572 0.508)
			(layers "F.Cu" "F.Mask" "F.Paste")
			(net "PSU1_CSAHRE")
		)
		(pad "2" smd rect
			(at -0.40005 0)
			(size 0.4572 0.508)
			(layers "F.Cu" "F.Mask" "F.Paste")
			(net "PSU_CSAHRE")
		)
	)
	(footprint ""
		(layer "F.Cu")
		(at 74.345292 -282.156154 -90)
		(property "Reference" "C45"
			(at 0.870204 -4.132834 90)
			(unlocked yes)
			(layer "F.SilkS")
			(effects
				(font
					(size 0.7874 0.5842)
					(thickness 0.1524)
				)
				(justify left)
			)
		)
		(property "Value" ""
			(at 0 0 270)
			(layer "F.Fab")
			(effects
				(font
					(size 1.27 1.27)
				)
			)
		)
		(duplicate_pad_numbers_are_jumpers no)
		(fp_line
			(start -0.7874 0.4064)
			(end -0.7874 -0.4064)
			(stroke
				(width 0.1524)
				(type default)
			)
			(layer "F.SilkS")
		)
		(fp_line
			(start 0.7874 0.4064)
			(end -0.7874 0.4064)
			(stroke
				(width 0.1524)
				(type default)
			)
			(layer "F.SilkS")
		)
		(fp_line
			(start 0 0.381)
			(end 0 -0.381)
			(stroke
				(width 0.1524)
				(type default)
			)
			(layer "F.SilkS")
		)
		(fp_line
			(start -0.7874 -0.4064)
			(end 0.7874 -0.4064)
			(stroke
				(width 0.1524)
				(type default)
			)
			(layer "F.SilkS")
		)
		(fp_line
			(start 0.7874 -0.4064)
			(end 0.7874 0.4064)
			(stroke
				(width 0.1524)
				(type default)
			)
			(layer "F.SilkS")
		)
		(fp_poly
			(pts
				(xy -0.5334 0.254) (xy -0.635 0.254) (xy -0.635 0.2286) (xy -0.635 -0.254) (xy -0.5334 -0.254) (xy -0.5334 -0.2794)
				(xy 0.5334 -0.2794) (xy 0.5334 -0.254) (xy 0.635 -0.254) (xy 0.635 0.254) (xy 0.5334 0.254) (xy 0.5334 0.2794)
				(xy -0.508 0.2794) (xy -0.5334 0.2794)
			)
			(stroke
				(width 0)
				(type default)
			)
			(fill no)
			(layer "F.CrtYd")
		)
		(pad "1" smd rect
			(at 0.40005 0 270)
			(size 0.4572 0.508)
			(layers "F.Cu" "F.Mask" "F.Paste")
			(net "P12V")
		)
		(pad "2" smd rect
			(at -0.40005 0 270)
			(size 0.4572 0.508)
			(layers "F.Cu" "F.Mask" "F.Paste")
			(net "GND")
		)
	)
	(footprint ""
		(layer "F.Cu")
		(at 26.102056 -274.774914)
		(property "Reference" "R74"
			(at -4.037838 -0.005334 0)
			(unlocked yes)
			(layer "F.SilkS")
			(effects
				(font
					(size 0.7874 0.5842)
					(thickness 0.1524)
				)
				(justify left)
			)
		)
		(property "Value" ""
			(at 0 0 0)
			(layer "F.Fab")
			(effects
				(font
					(size 1.27 1.27)
				)
			)
		)
		(duplicate_pad_numbers_are_jumpers no)
		(fp_line
			(start -0.7874 -0.4064)
			(end 0.7874 -0.4064)
			(stroke
				(width 0.1524)
				(type default)
			)
			(layer "F.SilkS")
		)
		(fp_line
			(start -0.7874 0.4064)
			(end -0.7874 -0.4064)
			(stroke
				(width 0.1524)
				(type default)
			)
			(layer "F.SilkS")
		)
		(fp_line
			(start 0.7874 -0.4064)
			(end 0.7874 0.4064)
			(stroke
				(width 0.1524)
				(type default)
			)
			(layer "F.SilkS")
		)
		(fp_line
			(start 0.7874 0.4064)
			(end -0.7874 0.4064)
			(stroke
				(width 0.1524)
				(type default)
			)
			(layer "F.SilkS")
		)
		(fp_poly
			(pts
				(xy -0.508 0.2794) (xy -0.508 0.2286) (xy -0.635 0.2286) (xy -0.635 -0.254) (xy -0.5334 -0.254)
				(xy -0.5334 -0.2794) (xy 0.5334 -0.2794) (xy 0.5334 -0.254) (xy 0.635 -0.254) (xy 0.635 0.254) (xy 0.5334 0.254)
				(xy 0.5334 0.2794)
			)
			(stroke
				(width 0)
				(type default)
			)
			(fill no)
			(layer "F.CrtYd")
		)
		(pad "1" smd rect
			(at 0.40005 0)
			(size 0.4572 0.508)
			(layers "F.Cu" "F.Mask" "F.Paste")
			(net "PSU4_PS_KILL")
		)
		(pad "2" smd rect
			(at -0.40005 0)
			(size 0.4572 0.508)
			(layers "F.Cu" "F.Mask" "F.Paste")
			(net "P12V_STBY")
		)
	)
)
